(kicad_pcb
	(version 20260206)
	(generator "pcbnew")
	(generator_version "10.0")
	(general
		(thickness 1.6)
		(legacy_teardrops no)
	)
	(paper "A4")
	(title_block
		(title "04192023_DAF0TMB3IC0_F0TG_MB_C_brd_V02_OCP.brd")
		(comment 1 "Grand Teton / footprints 7662-7668 of 8354")
	)
	(layers
		(0 "F.Cu" signal "TOP")
		(4 "In1.Cu" signal "GND")
		(6 "In2.Cu" signal "IN1")
		(8 "In3.Cu" signal "GND1")
		(10 "In4.Cu" signal "IN2")
		(12 "In5.Cu" signal "GND2")
		(14 "In6.Cu" signal "IN3")
		(16 "In7.Cu" signal "GND3")
		(18 "In8.Cu" signal "VCC")
		(20 "In9.Cu" signal "VCC1")
		(22 "In10.Cu" signal "GND4")
		(24 "In11.Cu" signal "IN4")
		(26 "In12.Cu" signal "GND5")
		(28 "In13.Cu" signal "IN5")
		(30 "In14.Cu" signal "GND6")
		(32 "In15.Cu" signal "IN6")
		(34 "In16.Cu" signal "GND7")
		(2 "B.Cu" signal "BOTTOM")
		(9 "F.Adhes" user "F.Adhesive")
		(11 "B.Adhes" user "B.Adhesive")
		(13 "F.Paste" user "Package Geometry/Pastemask Top")
		(15 "B.Paste" user "Package Geometry/Pastemask Bottom")
		(5 "F.SilkS" user "Ref Des/Silkscreen Top")
		(7 "B.SilkS" user "Ref Des/Silkscreen Bottom")
		(1 "F.Mask" user "Board Geometry/Soldermask Top")
		(3 "B.Mask" user "Board Geometry/Soldermask Bottom")
		(17 "Dwgs.User" user "User.Drawings")
		(19 "Cmts.User" user "User.Comments")
		(21 "Eco1.User" user "User.Eco1")
		(23 "Eco2.User" user "User.Eco2")
		(25 "Edge.Cuts" user "Board Geometry/Outline")
		(27 "Margin" user)
		(31 "F.CrtYd" user "Package Geometry/Place Bound Top")
		(29 "B.CrtYd" user "Package Geometry/Place Bound Bottom")
		(35 "F.Fab" user "Ref Des/Assembly Top")
		(33 "B.Fab" user "Ref Des/Assembly Bottom")
	)
	(footprint ""
		(layer "B.Cu")
		(at 178.689 -100.294948 -90)
		(property "Reference" "R141"
			(at 0 0 90)
			(layer "B.SilkS")
			(hide yes)
			(effects
				(font
					(size 1.27 1.27)
				)
				(justify mirror)
			)
		)
		(property "Value" ""
			(at 0 0 90)
			(layer "B.Fab")
			(effects
				(font
					(size 1.27 1.27)
				)
				(justify mirror)
			)
		)
		(duplicate_pad_numbers_are_jumpers no)
		(fp_line
			(start -0.7874 0.4064)
			(end 0.7874 0.4064)
			(stroke
				(width 0.1524)
				(type default)
			)
			(layer "B.SilkS")
		)
		(fp_line
			(start 0.7874 0.4064)
			(end 0.7874 -0.4064)
			(stroke
				(width 0.1524)
				(type default)
			)
			(layer "B.SilkS")
		)
		(fp_line
			(start -0.7874 -0.4064)
			(end -0.7874 0.4064)
			(stroke
				(width 0.1524)
				(type default)
			)
			(layer "B.SilkS")
		)
		(fp_line
			(start 0.7874 -0.4064)
			(end -0.7874 -0.4064)
			(stroke
				(width 0.1524)
				(type default)
			)
			(layer "B.SilkS")
		)
		(fp_line
			(start -0.67945 0.3048)
			(end -0.120396 0.3048)
			(stroke
				(width 0.1)
				(type default)
			)
			(layer "B.Fab")
		)
		(fp_line
			(start -0.120396 0.3048)
			(end -0.120396 0.2794)
			(stroke
				(width 0.1)
				(type default)
			)
			(layer "B.Fab")
		)
		(fp_line
			(start 0.12065 0.3048)
			(end 0.67945 0.3048)
			(stroke
				(width 0.1)
				(type default)
			)
			(layer "B.Fab")
		)
		(fp_line
			(start 0.67945 0.3048)
			(end 0.67945 -0.305054)
			(stroke
				(width 0.1)
				(type default)
			)
			(layer "B.Fab")
		)
		(fp_line
			(start -0.120396 0.2794)
			(end 0.12065 0.2794)
			(stroke
				(width 0.1)
				(type default)
			)
			(layer "B.Fab")
		)
		(fp_line
			(start 0.12065 0.2794)
			(end 0.12065 0.3048)
			(stroke
				(width 0.1)
				(type default)
			)
			(layer "B.Fab")
		)
		(fp_line
			(start -0.12065 -0.2794)
			(end -0.12065 -0.3048)
			(stroke
				(width 0.1)
				(type default)
			)
			(layer "B.Fab")
		)
		(fp_line
			(start 0.12065 -0.2794)
			(end -0.12065 -0.2794)
			(stroke
				(width 0.1)
				(type default)
			)
			(layer "B.Fab")
		)
		(fp_line
			(start -0.67945 -0.3048)
			(end -0.67945 0.3048)
			(stroke
				(width 0.1)
				(type default)
			)
			(layer "B.Fab")
		)
		(fp_line
			(start -0.12065 -0.3048)
			(end -0.67945 -0.3048)
			(stroke
				(width 0.1)
				(type default)
			)
			(layer "B.Fab")
		)
		(fp_line
			(start 0.12065 -0.305054)
			(end 0.12065 -0.2794)
			(stroke
				(width 0.1)
				(type default)
			)
			(layer "B.Fab")
		)
		(fp_line
			(start 0.67945 -0.305054)
			(end 0.12065 -0.305054)
			(stroke
				(width 0.1)
				(type default)
			)
			(layer "B.Fab")
		)
		(pad "1" smd circle
			(at 0.40005 0 90)
			(size 0 0)
			(layers "B.Cu" "B.Mask" "B.Paste")
			(net "PVDDCR_CPU1_P1_OCP_N")
		)
		(pad "2" smd circle
			(at -0.40005 0 90)
			(size 0 0)
			(layers "B.Cu" "B.Mask" "B.Paste")
			(net "FM_PVDDCR_CPU1_P1_OCP_N")
		)
	)
	(footprint ""
		(layer "B.Cu")
		(at 75.103228 -337.658202 -90)
		(property "Reference" "PR260"
			(at 0 0 90)
			(layer "B.SilkS")
			(hide yes)
			(effects
				(font
					(size 1.27 1.27)
				)
				(justify mirror)
			)
		)
		(property "Value" ""
			(at 0 0 90)
			(layer "B.Fab")
			(effects
				(font
					(size 1.27 1.27)
				)
				(justify mirror)
			)
		)
		(duplicate_pad_numbers_are_jumpers no)
		(fp_line
			(start -0.7874 0.4064)
			(end 0.7874 0.4064)
			(stroke
				(width 0.1524)
				(type default)
			)
			(layer "B.SilkS")
		)
		(fp_line
			(start 0.7874 0.4064)
			(end 0.7874 -0.4064)
			(stroke
				(width 0.1524)
				(type default)
			)
			(layer "B.SilkS")
		)
		(fp_line
			(start -0.7874 -0.4064)
			(end -0.7874 0.4064)
			(stroke
				(width 0.1524)
				(type default)
			)
			(layer "B.SilkS")
		)
		(fp_line
			(start 0.7874 -0.4064)
			(end -0.7874 -0.4064)
			(stroke
				(width 0.1524)
				(type default)
			)
			(layer "B.SilkS")
		)
		(fp_line
			(start -0.67945 0.3048)
			(end -0.120396 0.3048)
			(stroke
				(width 0.1)
				(type default)
			)
			(layer "B.Fab")
		)
		(fp_line
			(start -0.120396 0.3048)
			(end -0.120396 0.2794)
			(stroke
				(width 0.1)
				(type default)
			)
			(layer "B.Fab")
		)
		(fp_line
			(start 0.12065 0.3048)
			(end 0.67945 0.3048)
			(stroke
				(width 0.1)
				(type default)
			)
			(layer "B.Fab")
		)
		(fp_line
			(start 0.67945 0.3048)
			(end 0.67945 -0.305054)
			(stroke
				(width 0.1)
				(type default)
			)
			(layer "B.Fab")
		)
		(fp_line
			(start -0.120396 0.2794)
			(end 0.12065 0.2794)
			(stroke
				(width 0.1)
				(type default)
			)
			(layer "B.Fab")
		)
		(fp_line
			(start 0.12065 0.2794)
			(end 0.12065 0.3048)
			(stroke
				(width 0.1)
				(type default)
			)
			(layer "B.Fab")
		)
		(fp_line
			(start -0.12065 -0.2794)
			(end -0.12065 -0.3048)
			(stroke
				(width 0.1)
				(type default)
			)
			(layer "B.Fab")
		)
		(fp_line
			(start 0.12065 -0.2794)
			(end -0.12065 -0.2794)
			(stroke
				(width 0.1)
				(type default)
			)
			(layer "B.Fab")
		)
		(fp_line
			(start -0.67945 -0.3048)
			(end -0.67945 0.3048)
			(stroke
				(width 0.1)
				(type default)
			)
			(layer "B.Fab")
		)
		(fp_line
			(start -0.12065 -0.3048)
			(end -0.67945 -0.3048)
			(stroke
				(width 0.1)
				(type default)
			)
			(layer "B.Fab")
		)
		(fp_line
			(start 0.12065 -0.305054)
			(end 0.12065 -0.2794)
			(stroke
				(width 0.1)
				(type default)
			)
			(layer "B.Fab")
		)
		(fp_line
			(start 0.67945 -0.305054)
			(end 0.12065 -0.305054)
			(stroke
				(width 0.1)
				(type default)
			)
			(layer "B.Fab")
		)
		(pad "1" smd circle
			(at 0.40005 0 90)
			(size 0 0)
			(layers "B.Cu" "B.Mask" "B.Paste")
			(net "PVDDCR_CPU1_P1_VOS2")
		)
		(pad "2" smd circle
			(at -0.40005 0 90)
			(size 0 0)
			(layers "B.Cu" "B.Mask" "B.Paste")
			(net "PVDDCR_CPU1_P1")
		)
	)
	(footprint ""
		(layer "B.Cu")
		(at 436.997348 -19.07667 -90)
		(property "Reference" "R1898"
			(at 0 0 90)
			(layer "B.SilkS")
			(hide yes)
			(effects
				(font
					(size 1.27 1.27)
				)
				(justify mirror)
			)
		)
		(property "Value" ""
			(at 0 0 90)
			(layer "B.Fab")
			(effects
				(font
					(size 1.27 1.27)
				)
				(justify mirror)
			)
		)
		(duplicate_pad_numbers_are_jumpers no)
		(fp_line
			(start -0.7874 0.4064)
			(end 0.7874 0.4064)
			(stroke
				(width 0.1524)
				(type default)
			)
			(layer "B.SilkS")
		)
		(fp_line
			(start 0.7874 0.4064)
			(end 0.7874 -0.4064)
			(stroke
				(width 0.1524)
				(type default)
			)
			(layer "B.SilkS")
		)
		(fp_line
			(start -0.7874 -0.4064)
			(end -0.7874 0.4064)
			(stroke
				(width 0.1524)
				(type default)
			)
			(layer "B.SilkS")
		)
		(fp_line
			(start 0.7874 -0.4064)
			(end -0.7874 -0.4064)
			(stroke
				(width 0.1524)
				(type default)
			)
			(layer "B.SilkS")
		)
		(fp_line
			(start -0.67945 0.3048)
			(end -0.120396 0.3048)
			(stroke
				(width 0.1)
				(type default)
			)
			(layer "B.Fab")
		)
		(fp_line
			(start -0.120396 0.3048)
			(end -0.120396 0.2794)
			(stroke
				(width 0.1)
				(type default)
			)
			(layer "B.Fab")
		)
		(fp_line
			(start 0.12065 0.3048)
			(end 0.67945 0.3048)
			(stroke
				(width 0.1)
				(type default)
			)
			(layer "B.Fab")
		)
		(fp_line
			(start 0.67945 0.3048)
			(end 0.67945 -0.305054)
			(stroke
				(width 0.1)
				(type default)
			)
			(layer "B.Fab")
		)
		(fp_line
			(start -0.120396 0.2794)
			(end 0.12065 0.2794)
			(stroke
				(width 0.1)
				(type default)
			)
			(layer "B.Fab")
		)
		(fp_line
			(start 0.12065 0.2794)
			(end 0.12065 0.3048)
			(stroke
				(width 0.1)
				(type default)
			)
			(layer "B.Fab")
		)
		(fp_line
			(start -0.12065 -0.2794)
			(end -0.12065 -0.3048)
			(stroke
				(width 0.1)
				(type default)
			)
			(layer "B.Fab")
		)
		(fp_line
			(start 0.12065 -0.2794)
			(end -0.12065 -0.2794)
			(stroke
				(width 0.1)
				(type default)
			)
			(layer "B.Fab")
		)
		(fp_line
			(start -0.67945 -0.3048)
			(end -0.67945 0.3048)
			(stroke
				(width 0.1)
				(type default)
			)
			(layer "B.Fab")
		)
		(fp_line
			(start -0.12065 -0.3048)
			(end -0.67945 -0.3048)
			(stroke
				(width 0.1)
				(type default)
			)
			(layer "B.Fab")
		)
		(fp_line
			(start 0.12065 -0.305054)
			(end 0.12065 -0.2794)
			(stroke
				(width 0.1)
				(type default)
			)
			(layer "B.Fab")
		)
		(fp_line
			(start 0.67945 -0.305054)
			(end 0.12065 -0.305054)
			(stroke
				(width 0.1)
				(type default)
			)
			(layer "B.Fab")
		)
		(pad "1" smd circle
			(at 0.40005 0 90)
			(size 0 0)
			(layers "B.Cu" "B.Mask" "B.Paste")
			(net "OCP_SFF_ISO_BIF2_EN")
		)
		(pad "2" smd circle
			(at -0.40005 0 90)
			(size 0 0)
			(layers "B.Cu" "B.Mask" "B.Paste")
			(net "GND")
		)
	)
	(footprint ""
		(layer "B.Cu")
		(at 440.40171 -14.643354)
		(property "Reference" "C21"
			(at 0 0 0)
			(layer "B.SilkS")
			(hide yes)
			(effects
				(font
					(size 1.27 1.27)
				)
				(justify mirror)
			)
		)
		(property "Value" ""
			(at 0 0 0)
			(layer "B.Fab")
			(effects
				(font
					(size 1.27 1.27)
				)
				(justify mirror)
			)
		)
		(duplicate_pad_numbers_are_jumpers no)
		(fp_line
			(start -0.7874 -0.4064)
			(end -0.7874 0.4064)
			(stroke
				(width 0.1524)
				(type default)
			)
			(layer "B.SilkS")
		)
		(fp_line
			(start -0.7874 0.4064)
			(end 0.7874 0.4064)
			(stroke
				(width 0.1524)
				(type default)
			)
			(layer "B.SilkS")
		)
		(fp_line
			(start 0.7874 -0.4064)
			(end -0.7874 -0.4064)
			(stroke
				(width 0.1524)
				(type default)
			)
			(layer "B.SilkS")
		)
		(fp_line
			(start 0.7874 0.4064)
			(end 0.7874 -0.4064)
			(stroke
				(width 0.1524)
				(type default)
			)
			(layer "B.SilkS")
		)
		(fp_line
			(start -0.67945 -0.3048)
			(end -0.67945 0.3048)
			(stroke
				(width 0.1)
				(type default)
			)
			(layer "B.Fab")
		)
		(fp_line
			(start -0.67945 0.3048)
			(end -0.120396 0.3048)
			(stroke
				(width 0.1)
				(type default)
			)
			(layer "B.Fab")
		)
		(fp_line
			(start -0.12065 -0.3048)
			(end -0.67945 -0.3048)
			(stroke
				(width 0.1)
				(type default)
			)
			(layer "B.Fab")
		)
		(fp_line
			(start -0.12065 -0.2794)
			(end -0.12065 -0.3048)
			(stroke
				(width 0.1)
				(type default)
			)
			(layer "B.Fab")
		)
		(fp_line
			(start -0.120396 0.2794)
			(end 0.12065 0.2794)
			(stroke
				(width 0.1)
				(type default)
			)
			(layer "B.Fab")
		)
		(fp_line
			(start -0.120396 0.3048)
			(end -0.120396 0.2794)
			(stroke
				(width 0.1)
				(type default)
			)
			(layer "B.Fab")
		)
		(fp_line
			(start 0.12065 -0.305054)
			(end 0.12065 -0.2794)
			(stroke
				(width 0.1)
				(type default)
			)
			(layer "B.Fab")
		)
		(fp_line
			(start 0.12065 -0.2794)
			(end -0.12065 -0.2794)
			(stroke
				(width 0.1)
				(type default)
			)
			(layer "B.Fab")
		)
		(fp_line
			(start 0.12065 0.2794)
			(end 0.12065 0.3048)
			(stroke
				(width 0.1)
				(type default)
			)
			(layer "B.Fab")
		)
		(fp_line
			(start 0.12065 0.3048)
			(end 0.67945 0.3048)
			(stroke
				(width 0.1)
				(type default)
			)
			(layer "B.Fab")
		)
		(fp_line
			(start 0.67945 -0.305054)
			(end 0.12065 -0.305054)
			(stroke
				(width 0.1)
				(type default)
			)
			(layer "B.Fab")
		)
		(fp_line
			(start 0.67945 0.3048)
			(end 0.67945 -0.305054)
			(stroke
				(width 0.1)
				(type default)
			)
			(layer "B.Fab")
		)
		(pad "1" smd circle
			(at 0.40005 0 180)
			(size 0 0)
			(layers "B.Cu" "B.Mask" "B.Paste")
			(net "P12V_OCP_SFF_R")
		)
		(pad "2" smd circle
			(at -0.40005 0 180)
			(size 0 0)
			(layers "B.Cu" "B.Mask" "B.Paste")
			(net "GND")
		)
	)
	(footprint ""
		(layer "B.Cu")
		(at 56.073802 -194.885564 180)
		(property "Reference" "R36"
			(at 0 0 0)
			(layer "B.SilkS")
			(hide yes)
			(effects
				(font
					(size 1.27 1.27)
				)
				(justify mirror)
			)
		)
		(property "Value" ""
			(at 0 0 0)
			(layer "B.Fab")
			(effects
				(font
					(size 1.27 1.27)
				)
				(justify mirror)
			)
		)
		(duplicate_pad_numbers_are_jumpers no)
		(fp_line
			(start 0.7874 0.4064)
			(end 0.7874 -0.4064)
			(stroke
				(width 0.1524)
				(type default)
			)
			(layer "B.SilkS")
		)
		(fp_line
			(start 0.7874 -0.4064)
			(end -0.7874 -0.4064)
			(stroke
				(width 0.1524)
				(type default)
			)
			(layer "B.SilkS")
		)
		(fp_line
			(start -0.7874 0.4064)
			(end 0.7874 0.4064)
			(stroke
				(width 0.1524)
				(type default)
			)
			(layer "B.SilkS")
		)
		(fp_line
			(start -0.7874 -0.4064)
			(end -0.7874 0.4064)
			(stroke
				(width 0.1524)
				(type default)
			)
			(layer "B.SilkS")
		)
		(fp_line
			(start 0.67945 0.3048)
			(end 0.67945 -0.305054)
			(stroke
				(width 0.1)
				(type default)
			)
			(layer "B.Fab")
		)
		(fp_line
			(start 0.67945 -0.305054)
			(end 0.12065 -0.305054)
			(stroke
				(width 0.1)
				(type default)
			)
			(layer "B.Fab")
		)
		(fp_line
			(start 0.12065 0.3048)
			(end 0.67945 0.3048)
			(stroke
				(width 0.1)
				(type default)
			)
			(layer "B.Fab")
		)
		(fp_line
			(start 0.12065 0.2794)
			(end 0.12065 0.3048)
			(stroke
				(width 0.1)
				(type default)
			)
			(layer "B.Fab")
		)
		(fp_line
			(start 0.12065 -0.2794)
			(end -0.12065 -0.2794)
			(stroke
				(width 0.1)
				(type default)
			)
			(layer "B.Fab")
		)
		(fp_line
			(start 0.12065 -0.305054)
			(end 0.12065 -0.2794)
			(stroke
				(width 0.1)
				(type default)
			)
			(layer "B.Fab")
		)
		(fp_line
			(start -0.120396 0.3048)
			(end -0.120396 0.2794)
			(stroke
				(width 0.1)
				(type default)
			)
			(layer "B.Fab")
		)
		(fp_line
			(start -0.120396 0.2794)
			(end 0.12065 0.2794)
			(stroke
				(width 0.1)
				(type default)
			)
			(layer "B.Fab")
		)
		(fp_line
			(start -0.12065 -0.2794)
			(end -0.12065 -0.3048)
			(stroke
				(width 0.1)
				(type default)
			)
			(layer "B.Fab")
		)
		(fp_line
			(start -0.12065 -0.3048)
			(end -0.67945 -0.3048)
			(stroke
				(width 0.1)
				(type default)
			)
			(layer "B.Fab")
		)
		(fp_line
			(start -0.67945 0.3048)
			(end -0.120396 0.3048)
			(stroke
				(width 0.1)
				(type default)
			)
			(layer "B.Fab")
		)
		(fp_line
			(start -0.67945 -0.3048)
			(end -0.67945 0.3048)
			(stroke
				(width 0.1)
				(type default)
			)
			(layer "B.Fab")
		)
		(pad "1" smd circle
			(at 0.40005 0)
			(size 0 0)
			(layers "B.Cu" "B.Mask" "B.Paste")
			(net "PD_CHA_CPU1_DIMM0_SAA")
		)
		(pad "2" smd circle
			(at -0.40005 0)
			(size 0 0)
			(layers "B.Cu" "B.Mask" "B.Paste")
			(net "GND")
		)
	)
	(footprint ""
		(layer "B.Cu")
		(at 295.402 -427.228 180)
		(property "Reference" "R1211"
			(at 0 0 0)
			(layer "B.SilkS")
			(hide yes)
			(effects
				(font
					(size 1.27 1.27)
				)
				(justify mirror)
			)
		)
		(property "Value" ""
			(at 0 0 0)
			(layer "B.Fab")
			(effects
				(font
					(size 1.27 1.27)
				)
				(justify mirror)
			)
		)
		(duplicate_pad_numbers_are_jumpers no)
		(fp_line
			(start 0.32512 0.175006)
			(end 0.32512 -0.175006)
			(stroke
				(width 0.1)
				(type default)
			)
			(layer "B.Fab")
		)
		(fp_line
			(start 0.32512 -0.175006)
			(end -0.32512 -0.175006)
			(stroke
				(width 0.1)
				(type default)
			)
			(layer "B.Fab")
		)
		(fp_line
			(start -0.32512 0.175006)
			(end 0.32512 0.175006)
			(stroke
				(width 0.1)
				(type default)
			)
			(layer "B.Fab")
		)
		(fp_line
			(start -0.32512 -0.175006)
			(end -0.32512 0.175006)
			(stroke
				(width 0.1)
				(type default)
			)
			(layer "B.Fab")
		)
		(pad "1" smd rect
			(at 0.2667 0)
			(size 0.3048 0.381)
			(layers "B.Cu" "B.Mask" "B.Paste")
			(net "RST_SMB_RT_ROM_R1_N")
		)
		(pad "2" smd rect
			(at -0.2667 0 180)
			(size 0.3048 0.381)
			(layers "B.Cu" "B.Mask" "B.Paste")
			(net "FM_SMB_RT_ROM_MUX5_SEL")
		)
	)
	(footprint ""
		(layer "B.Cu")
		(at 314.68441 -337.660488 -90)
		(property "Reference" "PR92"
			(at 0 0 90)
			(layer "B.SilkS")
			(hide yes)
			(effects
				(font
					(size 1.27 1.27)
				)
				(justify mirror)
			)
		)
		(property "Value" ""
			(at 0 0 90)
			(layer "B.Fab")
			(effects
				(font
					(size 1.27 1.27)
				)
				(justify mirror)
			)
		)
		(duplicate_pad_numbers_are_jumpers no)
		(fp_line
			(start -0.7874 0.4064)
			(end 0.7874 0.4064)
			(stroke
				(width 0.1524)
				(type default)
			)
			(layer "B.SilkS")
		)
		(fp_line
			(start 0.7874 0.4064)
			(end 0.7874 -0.4064)
			(stroke
				(width 0.1524)
				(type default)
			)
			(layer "B.SilkS")
		)
		(fp_line
			(start -0.7874 -0.4064)
			(end -0.7874 0.4064)
			(stroke
				(width 0.1524)
				(type default)
			)
			(layer "B.SilkS")
		)
		(fp_line
			(start 0.7874 -0.4064)
			(end -0.7874 -0.4064)
			(stroke
				(width 0.1524)
				(type default)
			)
			(layer "B.SilkS")
		)
		(fp_line
			(start -0.67945 0.3048)
			(end -0.120396 0.3048)
			(stroke
				(width 0.1)
				(type default)
			)
			(layer "B.Fab")
		)
		(fp_line
			(start -0.120396 0.3048)
			(end -0.120396 0.2794)
			(stroke
				(width 0.1)
				(type default)
			)
			(layer "B.Fab")
		)
		(fp_line
			(start 0.12065 0.3048)
			(end 0.67945 0.3048)
			(stroke
				(width 0.1)
				(type default)
			)
			(layer "B.Fab")
		)
		(fp_line
			(start 0.67945 0.3048)
			(end 0.67945 -0.305054)
			(stroke
				(width 0.1)
				(type default)
			)
			(layer "B.Fab")
		)
		(fp_line
			(start -0.120396 0.2794)
			(end 0.12065 0.2794)
			(stroke
				(width 0.1)
				(type default)
			)
			(layer "B.Fab")
		)
		(fp_line
			(start 0.12065 0.2794)
			(end 0.12065 0.3048)
			(stroke
				(width 0.1)
				(type default)
			)
			(layer "B.Fab")
		)
		(fp_line
			(start -0.12065 -0.2794)
			(end -0.12065 -0.3048)
			(stroke
				(width 0.1)
				(type default)
			)
			(layer "B.Fab")
		)
		(fp_line
			(start 0.12065 -0.2794)
			(end -0.12065 -0.2794)
			(stroke
				(width 0.1)
				(type default)
			)
			(layer "B.Fab")
		)
		(fp_line
			(start -0.67945 -0.3048)
			(end -0.67945 0.3048)
			(stroke
				(width 0.1)
				(type default)
			)
			(layer "B.Fab")
		)
		(fp_line
			(start -0.12065 -0.3048)
			(end -0.67945 -0.3048)
			(stroke
				(width 0.1)
				(type default)
			)
			(layer "B.Fab")
		)
		(fp_line
			(start 0.12065 -0.305054)
			(end 0.12065 -0.2794)
			(stroke
				(width 0.1)
				(type default)
			)
			(layer "B.Fab")
		)
		(fp_line
			(start 0.67945 -0.305054)
			(end 0.12065 -0.305054)
			(stroke
				(width 0.1)
				(type default)
			)
			(layer "B.Fab")
		)
		(pad "1" smd circle
			(at 0.40005 0 90)
			(size 0 0)
			(layers "B.Cu" "B.Mask" "B.Paste")
			(net "PVDDCR_CPU1_P0_VOS3")
		)
		(pad "2" smd circle
			(at -0.40005 0 90)
			(size 0 0)
			(layers "B.Cu" "B.Mask" "B.Paste")
			(net "PVDDCR_CPU1_P0")
		)
	)
)
